# T6G (Grand Teton) — schematic netlist excerpt (pin names and nets, part order shuffled) for the footprints in the layout excerpt that follows; sources: Cadence DE-HDL packaged netlist, KiCad conversion of 04192023_DAF0TMB3IC0_F0TG_MB_C_brd_V02_OCP.brd

R6742  Q_RES  1K 1% EMPTY  pkg 0402LF  page 358 : A = P1V8_AUX ; B = RT_BOARD_ID_ID1
R5014  Q_RES  1K 1% EMPTY  pkg 0402LF  page 159 : A = PVDD11_S3_P0 ; B = I3C_SCM_0_R_SCL

(kicad_pcb
	(version 20260206)
	(generator "pcbnew")
	(generator_version "10.0")
	(general
		(thickness 1.6)
		(legacy_teardrops no)
	)
	(paper "A4")
	(title_block
		(title "04192023_DAF0TMB3IC0_F0TG_MB_C_brd_V02_OCP.brd")
		(comment 1 "Grand Teton / footprints 4774-4775 of 8354")
	)
	(layers
		(0 "F.Cu" signal "TOP")
		(4 "In1.Cu" signal "GND")
		(6 "In2.Cu" signal "IN1")
		(8 "In3.Cu" signal "GND1")
		(10 "In4.Cu" signal "IN2")
		(12 "In5.Cu" signal "GND2")
		(14 "In6.Cu" signal "IN3")
		(16 "In7.Cu" signal "GND3")
		(18 "In8.Cu" signal "VCC")
		(20 "In9.Cu" signal "VCC1")
		(22 "In10.Cu" signal "GND4")
		(24 "In11.Cu" signal "IN4")
		(26 "In12.Cu" signal "GND5")
		(28 "In13.Cu" signal "IN5")
		(30 "In14.Cu" signal "GND6")
		(32 "In15.Cu" signal "IN6")
		(34 "In16.Cu" signal "GND7")
		(2 "B.Cu" signal "BOTTOM")
		(9 "F.Adhes" user "F.Adhesive")
		(11 "B.Adhes" user "B.Adhesive")
		(13 "F.Paste" user "Package Geometry/Pastemask Top")
		(15 "B.Paste" user "Package Geometry/Pastemask Bottom")
		(5 "F.SilkS" user "Ref Des/Silkscreen Top")
		(7 "B.SilkS" user "Ref Des/Silkscreen Bottom")
		(1 "F.Mask" user "Board Geometry/Soldermask Top")
		(3 "B.Mask" user "Board Geometry/Soldermask Bottom")
		(17 "Dwgs.User" user "User.Drawings")
		(19 "Cmts.User" user "User.Comments")
		(21 "Eco1.User" user "User.Eco1")
		(23 "Eco2.User" user "User.Eco2")
		(25 "Edge.Cuts" user "Board Geometry/Outline")
		(27 "Margin" user)
		(31 "F.CrtYd" user "Package Geometry/Place Bound Top")
		(29 "B.CrtYd" user "Package Geometry/Place Bound Bottom")
		(35 "F.Fab" user "Ref Des/Assembly Top")
		(33 "B.Fab" user "Ref Des/Assembly Bottom")
	)
	(footprint ""
		(layer "F.Cu")
		(at 178.69408 -92.685616 90)
		(property "Reference" "R6742"
			(at 0 0 90)
			(layer "F.SilkS")
			(hide yes)
			(effects
				(font
					(size 1.27 1.27)
				)
			)
		)
		(property "Value" ""
			(at 0 0 90)
			(layer "F.Fab")
			(effects
				(font
					(size 1.27 1.27)
				)
			)
		)
		(duplicate_pad_numbers_are_jumpers no)
		(fp_line
			(start 0.7874 -0.4064)
			(end 0.7874 0.4064)
			(stroke
				(width 0.1524)
				(type default)
			)
			(layer "F.SilkS")
		)
		(fp_line
			(start -0.7874 -0.4064)
			(end 0.7874 -0.4064)
			(stroke
				(width 0.1524)
				(type default)
			)
			(layer "F.SilkS")
		)
		(fp_line
			(start 0.7874 0.4064)
			(end -0.7874 0.4064)
			(stroke
				(width 0.1524)
				(type default)
			)
			(layer "F.SilkS")
		)
		(fp_line
			(start -0.7874 0.4064)
			(end -0.7874 -0.4064)
			(stroke
				(width 0.1524)
				(type default)
			)
			(layer "F.SilkS")
		)
		(fp_line
			(start -0.12065 -0.305054)
			(end -0.12065 -0.2794)
			(stroke
				(width 0.1)
				(type default)
			)
			(layer "F.Fab")
		)
		(fp_line
			(start -0.67945 -0.305054)
			(end -0.12065 -0.305054)
			(stroke
				(width 0.1)
				(type default)
			)
			(layer "F.Fab")
		)
		(fp_line
			(start 0.67945 -0.3048)
			(end 0.67945 0.3048)
			(stroke
				(width 0.1)
				(type default)
			)
			(layer "F.Fab")
		)
		(fp_line
			(start 0.12065 -0.3048)
			(end 0.67945 -0.3048)
			(stroke
				(width 0.1)
				(type default)
			)
			(layer "F.Fab")
		)
		(fp_line
			(start 0.12065 -0.2794)
			(end 0.12065 -0.3048)
			(stroke
				(width 0.1)
				(type default)
			)
			(layer "F.Fab")
		)
		(fp_line
			(start -0.12065 -0.2794)
			(end 0.12065 -0.2794)
			(stroke
				(width 0.1)
				(type default)
			)
			(layer "F.Fab")
		)
		(fp_line
			(start 0.120396 0.2794)
			(end -0.12065 0.2794)
			(stroke
				(width 0.1)
				(type default)
			)
			(layer "F.Fab")
		)
		(fp_line
			(start -0.12065 0.2794)
			(end -0.12065 0.3048)
			(stroke
				(width 0.1)
				(type default)
			)
			(layer "F.Fab")
		)
		(fp_line
			(start 0.67945 0.3048)
			(end 0.120396 0.3048)
			(stroke
				(width 0.1)
				(type default)
			)
			(layer "F.Fab")
		)
		(fp_line
			(start 0.120396 0.3048)
			(end 0.120396 0.2794)
			(stroke
				(width 0.1)
				(type default)
			)
			(layer "F.Fab")
		)
		(fp_line
			(start -0.12065 0.3048)
			(end -0.67945 0.3048)
			(stroke
				(width 0.1)
				(type default)
			)
			(layer "F.Fab")
		)
		(fp_line
			(start -0.67945 0.3048)
			(end -0.67945 -0.305054)
			(stroke
				(width 0.1)
				(type default)
			)
			(layer "F.Fab")
		)
		(pad "1" smd circle
			(at -0.40005 0 90)
			(size 0 0)
			(layers "F.Cu" "F.Mask" "F.Paste")
			(net "P1V8_AUX")
		)
		(pad "2" smd circle
			(at 0.40005 0 90)
			(size 0 0)
			(layers "F.Cu" "F.Mask" "F.Paste")
			(net "RT_BOARD_ID_ID1")
		)
	)
	(footprint ""
		(layer "F.Cu")
		(at 305.082448 -147.940522 180)
		(property "Reference" "R5014"
			(at 0 0 180)
			(layer "F.SilkS")
			(hide yes)
			(effects
				(font
					(size 1.27 1.27)
				)
			)
		)
		(property "Value" ""
			(at 0 0 180)
			(layer "F.Fab")
			(effects
				(font
					(size 1.27 1.27)
				)
			)
		)
		(duplicate_pad_numbers_are_jumpers no)
		(fp_line
			(start 0.7874 0.4064)
			(end -0.7874 0.4064)
			(stroke
				(width 0.1524)
				(type default)
			)
			(layer "F.SilkS")
		)
		(fp_line
			(start 0.7874 -0.4064)
			(end 0.7874 0.4064)
			(stroke
				(width 0.1524)
				(type default)
			)
			(layer "F.SilkS")
		)
		(fp_line
			(start -0.7874 0.4064)
			(end -0.7874 -0.4064)
			(stroke
				(width 0.1524)
				(type default)
			)
			(layer "F.SilkS")
		)
		(fp_line
			(start -0.7874 -0.4064)
			(end 0.7874 -0.4064)
			(stroke
				(width 0.1524)
				(type default)
			)
			(layer "F.SilkS")
		)
		(fp_line
			(start 0.67945 0.3048)
			(end 0.120396 0.3048)
			(stroke
				(width 0.1)
				(type default)
			)
			(layer "F.Fab")
		)
		(fp_line
			(start 0.67945 -0.3048)
			(end 0.67945 0.3048)
			(stroke
				(width 0.1)
				(type default)
			)
			(layer "F.Fab")
		)
		(fp_line
			(start 0.12065 -0.2794)
			(end 0.12065 -0.3048)
			(stroke
				(width 0.1)
				(type default)
			)
			(layer "F.Fab")
		)
		(fp_line
			(start 0.12065 -0.3048)
			(end 0.67945 -0.3048)
			(stroke
				(width 0.1)
				(type default)
			)
			(layer "F.Fab")
		)
		(fp_line
			(start 0.120396 0.3048)
			(end 0.120396 0.2794)
			(stroke
				(width 0.1)
				(type default)
			)
			(layer "F.Fab")
		)
		(fp_line
			(start 0.120396 0.2794)
			(end -0.12065 0.2794)
			(stroke
				(width 0.1)
				(type default)
			)
			(layer "F.Fab")
		)
		(fp_line
			(start -0.12065 0.3048)
			(end -0.67945 0.3048)
			(stroke
				(width 0.1)
				(type default)
			)
			(layer "F.Fab")
		)
		(fp_line
			(start -0.12065 0.2794)
			(end -0.12065 0.3048)
			(stroke
				(width 0.1)
				(type default)
			)
			(layer "F.Fab")
		)
		(fp_line
			(start -0.12065 -0.2794)
			(end 0.12065 -0.2794)
			(stroke
				(width 0.1)
				(type default)
			)
			(layer "F.Fab")
		)
		(fp_line
			(start -0.12065 -0.305054)
			(end -0.12065 -0.2794)
			(stroke
				(width 0.1)
				(type default)
			)
			(layer "F.Fab")
		)
		(fp_line
			(start -0.67945 0.3048)
			(end -0.67945 -0.305054)
			(stroke
				(width 0.1)
				(type default)
			)
			(layer "F.Fab")
		)
		(fp_line
			(start -0.67945 -0.305054)
			(end -0.12065 -0.305054)
			(stroke
				(width 0.1)
				(type default)
			)
			(layer "F.Fab")
		)
		(pad "1" smd circle
			(at -0.40005 0 180)
			(size 0 0)
			(layers "F.Cu" "F.Mask" "F.Paste")
			(net "PVDD11_S3_P0")
		)
		(pad "2" smd circle
			(at 0.40005 0 180)
			(size 0 0)
			(layers "F.Cu" "F.Mask" "F.Paste")
			(net "I3C_SCM_0_R_SCL")
		)
	)
)
